(kicad_pcb
	(version 20241229)
	(generator "pcbnew")
	(generator_version "9.0")
	(general
		(thickness 1.599998)
		(legacy_teardrops no)
	)
	(paper "A4")
	(title_block
		(date "2023-02-12")
		(rev "1.1.5")
		(comment 9 "footprints 234-238 of 473")
	)
	(layers
		(0 "F.Cu" signal)
		(4 "In1.Cu" power "In1.GND")
		(6 "In2.Cu" signal)
		(8 "In3.Cu" power "In3.GND")
		(10 "In4.Cu" power "In4.VCC")
		(12 "In5.Cu" signal)
		(14 "In6.Cu" power "In6.VCC")
		(2 "B.Cu" signal)
		(9 "F.Adhes" user "F.Adhesive")
		(11 "B.Adhes" user "B.Adhesive")
		(13 "F.Paste" user)
		(15 "B.Paste" user)
		(5 "F.SilkS" user "F.Silkscreen")
		(7 "B.SilkS" user "B.Silkscreen")
		(1 "F.Mask" user)
		(3 "B.Mask" user)
		(17 "Dwgs.User" user "User.Drawings")
		(19 "Cmts.User" user "User.Comments")
		(21 "Eco1.User" user "User.Eco1")
		(23 "Eco2.User" user "User.Eco2")
		(25 "Edge.Cuts" user)
		(27 "Margin" user)
		(31 "F.CrtYd" user "F.Courtyard")
		(29 "B.CrtYd" user "B.Courtyard")
		(35 "F.Fab" user)
		(33 "B.Fab" user)
	)
	(footprint "antmicro-footprints:SOT-523"
		(layer "F.Cu")
		(at 142.3825 87.099 90)
		(property "Reference" "Q10"
			(at 0.599 -2.5825 0)
			(layer "F.SilkS")
			(effects
				(font
					(size 0.7 0.7)
					(thickness 0.15)
				)
				(justify left bottom)
			)
		)
		(property "Value" "DMG1012T-7"
			(at 0.1 1.824 90)
			(layer "F.Fab")
			(effects
				(font
					(size 0.7 0.7)
					(thickness 0.15)
				)
				(justify left bottom)
			)
		)
		(property "Author" "Antmicro"
			(at 229.4815 -55.2835 0)
			(layer "F.Fab")
			(hide yes)
			(effects
				(font
					(size 1 1)
					(thickness 0.15)
				)
			)
		)
		(property "License" "Apache-2.0"
			(at 229.4815 -55.2835 0)
			(layer "F.Fab")
			(hide yes)
			(effects
				(font
					(size 1 1)
					(thickness 0.15)
				)
			)
		)
		(property "MPN" "DMG1012T-7"
			(at 229.4815 -55.2835 0)
			(layer "F.Fab")
			(hide yes)
			(effects
				(font
					(size 1 1)
					(thickness 0.15)
				)
			)
		)
		(property "Manufacturer" "Diodes Incorporated"
			(at 229.4815 -55.2835 0)
			(layer "F.Fab")
			(hide yes)
			(effects
				(font
					(size 1 1)
					(thickness 0.15)
				)
			)
		)
		(sheetname "Supply")
		(sheetfile "supply.kicad_sch")
		(attr smd)
		(fp_line
			(start -0.277 -0.551)
			(end -0.277 -0.75)
			(stroke
				(width 0.15)
				(type solid)
			)
			(layer "F.SilkS")
		)
		(fp_line
			(start -0.725 -0.551)
			(end -0.277 -0.551)
			(stroke
				(width 0.15)
				(type solid)
			)
			(layer "F.SilkS")
		)
		(fp_line
			(start -0.927 -0.351)
			(end -0.725 -0.551)
			(stroke
				(width 0.15)
				(type solid)
			)
			(layer "F.SilkS")
		)
		(fp_line
			(start -0.927 -0.051)
			(end -0.927 -0.351)
			(stroke
				(width 0.15)
				(type solid)
			)
			(layer "F.SilkS")
		)
		(fp_circle
			(center -0.9652 0.9652)
			(end -0.9152 0.9652)
			(stroke
				(width 0.15)
				(type solid)
			)
			(fill yes)
			(layer "F.SilkS")
		)
		(fp_line
			(start 1.1 -1.16)
			(end 1.1 1.15)
			(stroke
				(width 0.05)
				(type solid)
			)
			(layer "F.CrtYd")
		)
		(fp_line
			(start -1.12 -1.16)
			(end 1.1 -1.16)
			(stroke
				(width 0.05)
				(type solid)
			)
			(layer "F.CrtYd")
		)
		(fp_line
			(start -1.12 -1.16)
			(end -1.12 1.15)
			(stroke
				(width 0.05)
				(type solid)
			)
			(layer "F.CrtYd")
		)
		(fp_line
			(start -1.12 1.15)
			(end 1.1 1.15)
			(stroke
				(width 0.05)
				(type solid)
			)
			(layer "F.CrtYd")
		)
		(fp_line
			(start 0.8 -0.425)
			(end -0.652 -0.425)
			(stroke
				(width 0.15)
				(type solid)
			)
			(layer "F.Fab")
		)
		(fp_line
			(start 0.8 -0.425)
			(end 0.8 0.424)
			(stroke
				(width 0.15)
				(type solid)
			)
			(layer "F.Fab")
		)
		(fp_line
			(start -0.652 -0.425)
			(end -0.802 -0.276)
			(stroke
				(width 0.15)
				(type solid)
			)
			(layer "F.Fab")
		)
		(fp_line
			(start -0.802 -0.276)
			(end -0.802 0.424)
			(stroke
				(width 0.15)
				(type solid)
			)
			(layer "F.Fab")
		)
		(fp_line
			(start 0.8 0.424)
			(end -0.802 0.424)
			(stroke
				(width 0.15)
				(type solid)
			)
			(layer "F.Fab")
		)
		(fp_circle
			(center -0.9652 0.9652)
			(end -0.9144 0.9652)
			(stroke
				(width 0.15)
				(type solid)
			)
			(fill no)
			(layer "F.Fab")
		)
		(pad "1" smd rect
			(at -0.5 0.65 90)
			(size 0.4 0.51)
			(layers "F.Cu" "F.Mask" "F.Paste")
			(net 461 "1V1_SYS")
			(pinfunction "G")
			(pintype "bidirectional")
		)
		(pad "2" smd rect
			(at 0.498 0.65 90)
			(size 0.4 0.51)
			(layers "F.Cu" "F.Mask" "F.Paste")
			(net 5 "GND")
			(pinfunction "S")
			(pintype "bidirectional")
		)
		(pad "3" smd rect
			(at 0 -0.652 90)
			(size 0.4 0.51)
			(layers "F.Cu" "F.Mask" "F.Paste")
			(net 236 "Net-(Q10-D)")
			(pinfunction "D")
			(pintype "bidirectional")
		)
	)
	(footprint "antmicro-footprints:LED_0603_1608Metric_G"
		(layer "F.Cu")
		(at 137.7825 89.599)
		(descr "LED SMD 0603 Green")
		(tags "LED SMD 0603 Green")
		(property "Reference" "PWR2"
			(at -4.6825 -0.799 0)
			(layer "F.SilkS")
			(effects
				(font
					(size 0.7 0.7)
					(thickness 0.15)
				)
				(justify left bottom)
			)
		)
		(property "Value" "LED_G_0603_KP-1608CGCK"
			(at 0 1.6 0)
			(layer "F.Fab")
			(effects
				(font
					(size 0.7 0.7)
					(thickness 0.15)
				)
				(justify left bottom)
			)
		)
		(property "Author" "Antmicro"
			(at 0 0 0)
			(layer "F.Fab")
			(hide yes)
			(effects
				(font
					(size 1 1)
					(thickness 0.15)
				)
			)
		)
		(property "License" "Apache-2.0"
			(at 0 0 0)
			(layer "F.Fab")
			(hide yes)
			(effects
				(font
					(size 1 1)
					(thickness 0.15)
				)
			)
		)
		(property "MPN" "KP-1608CGCK"
			(at 0 0 0)
			(layer "F.Fab")
			(hide yes)
			(effects
				(font
					(size 1 1)
					(thickness 0.15)
				)
			)
		)
		(property "Manufacturer" "Kingbright"
			(at 0 0 0)
			(layer "F.Fab")
			(hide yes)
			(effects
				(font
					(size 1 1)
					(thickness 0.15)
				)
			)
		)
		(sheetname "Supply")
		(sheetfile "supply.kicad_sch")
		(attr smd)
		(fp_line
			(start -0.27 -0.35)
			(end 0.27 -0.35)
			(stroke
				(width 0.15)
				(type solid)
			)
			(layer "F.SilkS")
		)
		(fp_line
			(start -0.27 0.351)
			(end 0.27 0.351)
			(stroke
				(width 0.15)
				(type solid)
			)
			(layer "F.SilkS")
		)
		(fp_line
			(start -0.106328 -0.200008)
			(end -0.106328 0.199992)
			(stroke
				(width 0.1)
				(type solid)
			)
			(layer "F.SilkS")
		)
		(fp_line
			(start -0.106328 -0.200008)
			(end 0.093672 -8e-06)
			(stroke
				(width 0.1)
				(type solid)
			)
			(layer "F.SilkS")
		)
		(fp_line
			(start -0.106328 -8e-06)
			(end -0.29 0)
			(stroke
				(width 0.1)
				(type solid)
			)
			(layer "F.SilkS")
		)
		(fp_line
			(start 0.093672 -0.200008)
			(end 0.093672 0.199992)
			(stroke
				(width 0.1)
				(type solid)
			)
			(layer "F.SilkS")
		)
		(fp_line
			(start 0.093672 -8e-06)
			(end -0.106328 0.199992)
			(stroke
				(width 0.1)
				(type solid)
			)
			(layer "F.SilkS")
		)
		(fp_line
			(start 0.093672 -8e-06)
			(end 0.293672 -8e-06)
			(stroke
				(width 0.1)
				(type solid)
			)
			(layer "F.SilkS")
		)
		(fp_line
			(start 1.25 0.32)
			(end 1.25 -0.32)
			(stroke
				(width 0.15)
				(type solid)
			)
			(layer "F.SilkS")
		)
		(fp_rect
			(start 1.26 0.65)
			(end -1.26 -0.65)
			(stroke
				(width 0.05)
				(type solid)
			)
			(fill no)
			(layer "F.CrtYd")
		)
		(fp_line
			(start -0.599 0)
			(end -0.201 0)
			(stroke
				(width 0.15)
				(type solid)
			)
			(layer "F.Fab")
		)
		(fp_line
			(start -0.201 -0.2)
			(end -0.201 0)
			(stroke
				(width 0.15)
				(type solid)
			)
			(layer "F.Fab")
		)
		(fp_line
			(start -0.201 0)
			(end -0.201 0.202)
			(stroke
				(width 0.15)
				(type solid)
			)
			(layer "F.Fab")
		)
		(fp_line
			(start -0.201 0.202)
			(end 0.101 0)
			(stroke
				(width 0.15)
				(type solid)
			)
			(layer "F.Fab")
		)
		(fp_line
			(start 0.101 0)
			(end -0.201 -0.2)
			(stroke
				(width 0.15)
				(type solid)
			)
			(layer "F.Fab")
		)
		(fp_line
			(start 0.199 -0.2)
			(end 0.199 -0.1)
			(stroke
				(width 0.15)
				(type solid)
			)
			(layer "F.Fab")
		)
		(fp_line
			(start 0.199 0)
			(end 0.597 0)
			(stroke
				(width 0.15)
				(type solid)
			)
			(layer "F.Fab")
		)
		(fp_line
			(start 0.199 0.202)
			(end 0.199 -0.1)
			(stroke
				(width 0.15)
				(type solid)
			)
			(layer "F.Fab")
		)
		(fp_rect
			(start -0.848 -0.4)
			(end 0.85 0.402)
			(stroke
				(width 0.15)
				(type solid)
			)
			(fill no)
			(layer "F.Fab")
		)
		(pad "1" smd rect
			(at -0.75 0 180)
			(size 0.8 0.8)
			(layers "F.Cu" "F.Mask" "F.Paste")
			(net 459 "3V3_SYS")
			(pinfunction "1")
			(pintype "passive")
		)
		(pad "2" smd rect
			(at 0.75 0 180)
			(size 0.8 0.8)
			(layers "F.Cu" "F.Mask" "F.Paste")
			(net 553 "Net-(PWR2-Pad2)")
			(pinfunction "2")
			(pintype "passive")
		)
	)
	(footprint "antmicro-footprints:C_0402_1005Metric"
		(layer "F.Cu")
		(at 128.675 56.725 180)
		(descr "Capacitor SMD 0402")
		(tags "capacitor SMD 0402")
		(property "Reference" "C191"
			(at 1.216843 -1.312672 0)
			(layer "F.SilkS")
			(effects
				(font
					(size 0.7 0.7)
					(thickness 0.15)
				)
				(justify left bottom)
			)
		)
		(property "Value" "C_100n_6V3_0402"
			(at 0 1.4 180)
			(layer "F.Fab")
			(effects
				(font
					(size 0.7 0.7)
					(thickness 0.15)
				)
				(justify left bottom)
			)
		)
		(property "Description" " "
			(at 0 0 180)
			(layer "F.Fab")
			(hide yes)
			(effects
				(font
					(size 1.27 1.27)
					(thickness 0.15)
				)
			)
		)
		(property "Author" "Antmicro"
			(at 257.35 113.45 0)
			(layer "F.Fab")
			(hide yes)
			(effects
				(font
					(size 1 1)
					(thickness 0.15)
				)
			)
		)
		(property "Dielectric" ""
			(at 257.35 113.45 0)
			(layer "F.Fab")
			(hide yes)
			(effects
				(font
					(size 1 1)
					(thickness 0.15)
				)
			)
		)
		(property "License" "Apache-2.0"
			(at 257.35 113.45 0)
			(layer "F.Fab")
			(hide yes)
			(effects
				(font
					(size 1 1)
					(thickness 0.15)
				)
			)
		)
		(property "MPN" "0402X104K6R3CT"
			(at 257.35 113.45 0)
			(layer "F.Fab")
			(hide yes)
			(effects
				(font
					(size 1 1)
					(thickness 0.15)
				)
			)
		)
		(property "Manufacturer" "Walsin"
			(at 257.35 113.45 0)
			(layer "F.Fab")
			(hide yes)
			(effects
				(font
					(size 1 1)
					(thickness 0.15)
				)
			)
		)
		(property "Val" "100n"
			(at 257.35 113.45 0)
			(layer "F.Fab")
			(hide yes)
			(effects
				(font
					(size 1 1)
					(thickness 0.15)
				)
			)
		)
		(property "Voltage" ""
			(at 257.35 113.45 0)
			(layer "F.Fab")
			(hide yes)
			(effects
				(font
					(size 1 1)
					(thickness 0.15)
				)
			)
		)
		(sheetname "Supply")
		(sheetfile "supply.kicad_sch")
		(attr exclude_from_pos_files exclude_from_bom dnp)
		(fp_rect
			(start -0.94 -0.47)
			(end 0.94 0.47)
			(stroke
				(width 0.05)
				(type solid)
			)
			(fill no)
			(layer "F.CrtYd")
		)
		(fp_rect
			(start -0.499 -0.249)
			(end 0.499 0.249)
			(stroke
				(width 0.15)
				(type solid)
			)
			(fill no)
			(layer "F.Fab")
		)
		(pad "1" smd roundrect
			(at -0.484 0 180)
			(size 0.59 0.64)
			(layers "F.Cu" "F.Mask" "F.Paste")
			(roundrect_rratio 0.25)
			(net 659 "Net-(C191-Pad1)")
			(pintype "passive")
		)
		(pad "2" smd roundrect
			(at 0.484 0 180)
			(size 0.59 0.64)
			(layers "F.Cu" "F.Mask" "F.Paste")
			(roundrect_rratio 0.25)
			(net 625 "/Supply/VDD2_SW")
			(pintype "passive")
		)
	)
	(footprint "antmicro-footprints:Oscillator_SMD_Abracon_ASFL1-4Pin_5.0x3.2mm"
		(layer "F.Cu")
		(at 177.5 111.7 180)
		(property "Reference" "U2"
			(at -1.57 -3.108 180)
			(layer "F.SilkS")
			(effects
				(font
					(size 0.7 0.7)
					(thickness 0.15)
				)
				(justify left bottom)
			)
		)
		(property "Value" "ASFL1-100.000MHZ-L-T"
			(at -11.7 3.3 180)
			(layer "F.Fab")
			(effects
				(font
					(size 0.7 0.7)
					(thickness 0.15)
				)
				(justify left bottom)
			)
		)
		(property "Description" "Oscillator, 100 MHz, 100 ppm, SMT, 5mm x 3.2mm, 3.3 V, ASFL1 Series"
			(at 0 0 180)
			(layer "F.Fab")
			(hide yes)
			(effects
				(font
					(size 1.27 1.27)
					(thickness 0.15)
				)
			)
		)
		(property "Author" "Antmicro"
			(at 355 223.4 0)
			(layer "F.Fab")
			(hide yes)
			(effects
				(font
					(size 1 1)
					(thickness 0.15)
				)
			)
		)
		(property "License" "Apache-2.0"
			(at 355 223.4 0)
			(layer "F.Fab")
			(hide yes)
			(effects
				(font
					(size 1 1)
					(thickness 0.15)
				)
			)
		)
		(property "MPN" "ASFL1-100.000MHZ-L-T"
			(at 355 223.4 0)
			(layer "F.Fab")
			(hide yes)
			(effects
				(font
					(size 1 1)
					(thickness 0.15)
				)
			)
		)
		(property "Manufacturer" "Abracon"
			(at 355 223.4 0)
			(layer "F.Fab")
			(hide yes)
			(effects
				(font
					(size 1 1)
					(thickness 0.15)
				)
			)
		)
		(property "Val" "100 MHz"
			(at 355 223.4 0)
			(layer "F.Fab")
			(hide yes)
			(effects
				(font
					(size 1 1)
					(thickness 0.15)
				)
			)
		)
		(sheetname "FPGA Banks")
		(sheetfile "fpga-banks.kicad_sch")
		(attr smd)
		(fp_line
			(start 2.7 1.8)
			(end 2.298 1.8)
			(stroke
				(width 0.15)
				(type solid)
			)
			(layer "F.SilkS")
		)
		(fp_line
			(start 2.7 1.398)
			(end 2.7 1.8)
			(stroke
				(width 0.15)
				(type solid)
			)
			(layer "F.SilkS")
		)
		(fp_line
			(start 2.7 -1.801)
			(end 2.7 -1.401)
			(stroke
				(width 0.15)
				(type solid)
			)
			(layer "F.SilkS")
		)
		(fp_line
			(start 2.298 -1.801)
			(end 2.7 -1.801)
			(stroke
				(width 0.15)
				(type solid)
			)
			(layer "F.SilkS")
		)
		(fp_line
			(start -2.702 1.8)
			(end -2.702 1.398)
			(stroke
				(width 0.15)
				(type solid)
			)
			(layer "F.SilkS")
		)
		(fp_line
			(start -2.702 -1.401)
			(end -2.702 -1.801)
			(stroke
				(width 0.15)
				(type solid)
			)
			(layer "F.SilkS")
		)
		(fp_line
			(start -2.702 -1.801)
			(end -2.301 -1.801)
			(stroke
				(width 0.15)
				(type solid)
			)
			(layer "F.SilkS")
		)
		(fp_circle
			(center -2.4 2.1)
			(end -2.35 2.1)
			(stroke
				(width 0.15)
				(type solid)
			)
			(fill no)
			(layer "F.SilkS")
		)
		(fp_rect
			(start -3 -2.101)
			(end 2.999 2.1)
			(stroke
				(width 0.05)
				(type solid)
			)
			(fill no)
			(layer "F.CrtYd")
		)
		(fp_line
			(start -2 1.6)
			(end -2.5 1.1)
			(stroke
				(width 0.15)
				(type solid)
			)
			(layer "F.Fab")
		)
		(fp_line
			(start -2.1 1.6)
			(end -2.5 1.2)
			(stroke
				(width 0.15)
				(type solid)
			)
			(layer "F.Fab")
		)
		(fp_line
			(start -2.2 1.6)
			(end -2.5 1.3)
			(stroke
				(width 0.15)
				(type solid)
			)
			(layer "F.Fab")
		)
		(fp_line
			(start -2.3 1.6)
			(end -2.5 1.4)
			(stroke
				(width 0.15)
				(type solid)
			)
			(layer "F.Fab")
		)
		(fp_rect
			(start -2.5 -1.601)
			(end 2.499 1.6)
			(stroke
				(width 0.15)
				(type solid)
			)
			(fill no)
			(layer "F.Fab")
		)
		(pad "1" smd rect
			(at -1.27 1.1)
			(size 1.7 1.5)
			(layers "F.Cu" "F.Mask" "F.Paste")
			(net 459 "3V3_SYS")
			(pinfunction "EN")
			(pintype "input")
		)
		(pad "2" smd rect
			(at 1.269 1.1 180)
			(size 1.7 1.5)
			(layers "F.Cu" "F.Mask" "F.Paste")
			(net 5 "GND")
			(pinfunction "GND")
			(pintype "power_in")
		)
		(pad "3" smd rect
			(at 1.269 -1.101 180)
			(size 1.7 1.5)
			(layers "F.Cu" "F.Mask" "F.Paste")
			(net 38 "GCLK100")
			(pinfunction "OUT")
			(pintype "output")
		)
		(pad "4" smd rect
			(at -1.27 -1.101 180)
			(size 1.7 1.5)
			(layers "F.Cu" "F.Mask" "F.Paste")
			(net 459 "3V3_SYS")
			(pinfunction "VDD")
			(pintype "power_in")
		)
	)
	(footprint "antmicro-footprints:L_WE-MAIA-2512"
		(layer "F.Cu")
		(at 114.475 96.249 180)
		(property "Reference" "L2"
			(at -1.5 -1.4 180)
			(layer "F.SilkS")
			(effects
				(font
					(size 0.7 0.7)
					(thickness 0.15)
				)
				(justify left bottom)
			)
		)
		(property "Value" "784383240047"
			(at 0 2.3 180)
			(layer "F.Fab")
			(effects
				(font
					(size 0.7 0.7)
					(thickness 0.15)
				)
				(justify left bottom)
			)
		)
		(property "Description" "Power Inductor (SMT), AEC-Q200, 470 nH, 3.4 A, Shielded, 6.25 A, WE-MAIA"
			(at 0 0 180)
			(layer "F.Fab")
			(hide yes)
			(effects
				(font
					(size 1.27 1.27)
					(thickness 0.15)
				)
			)
		)
		(property "Author" "Antmicro"
			(at 228.95 192.498 0)
			(layer "F.Fab")
			(hide yes)
			(effects
				(font
					(size 1 1)
					(thickness 0.15)
				)
			)
		)
		(property "IMax" "3.4 A"
			(at 228.95 192.498 0)
			(layer "F.Fab")
			(hide yes)
			(effects
				(font
					(size 1 1)
					(thickness 0.15)
				)
			)
		)
		(property "ISat" "6.25 A"
			(at 228.95 192.498 0)
			(layer "F.Fab")
			(hide yes)
			(effects
				(font
					(size 1 1)
					(thickness 0.15)
				)
			)
		)
		(property "License" "Apache-2.0"
			(at 228.95 192.498 0)
			(layer "F.Fab")
			(hide yes)
			(effects
				(font
					(size 1 1)
					(thickness 0.15)
				)
			)
		)
		(property "MPN" "784383240047"
			(at 228.95 192.498 0)
			(layer "F.Fab")
			(hide yes)
			(effects
				(font
					(size 1 1)
					(thickness 0.15)
				)
			)
		)
		(property "Manufacturer" "Würth Elektronik"
			(at 228.95 192.498 0)
			(layer "F.Fab")
			(hide yes)
			(effects
				(font
					(size 1 1)
					(thickness 0.15)
				)
			)
		)
		(property "Size" "2x2.5"
			(at 228.95 192.498 0)
			(layer "F.Fab")
			(hide yes)
			(effects
				(font
					(size 1 1)
					(thickness 0.15)
				)
			)
		)
		(property "Val" "470n/3.4A"
			(at 228.95 192.498 0)
			(layer "F.Fab")
			(hide yes)
			(effects
				(font
					(size 1 1)
					(thickness 0.15)
				)
			)
		)
		(sheetname "Supply")
		(sheetfile "supply.kicad_sch")
		(attr smd)
		(fp_line
			(start -0.325 1.125)
			(end 0.325 1.125)
			(stroke
				(width 0.15)
				(type solid)
			)
			(layer "F.SilkS")
		)
		(fp_line
			(start -0.325 -1.125)
			(end 0.325 -1.125)
			(stroke
				(width 0.15)
				(type solid)
			)
			(layer "F.SilkS")
		)
		(fp_rect
			(start -1.65 -1.4)
			(end 1.65 1.4)
			(stroke
				(width 0.05)
				(type solid)
			)
			(fill no)
			(layer "F.CrtYd")
		)
		(fp_rect
			(start -1.25 -1)
			(end 1.25 1)
			(stroke
				(width 0.15)
				(type solid)
			)
			(fill no)
			(layer "F.Fab")
		)
		(pad "1" smd roundrect
			(at -0.975 0 180)
			(size 0.85 2.3)
			(layers "F.Cu" "F.Mask" "F.Paste")
			(roundrect_rratio 0.1)
			(net 575 "/Supply/3V3_SW")
			(pintype "passive")
		)
		(pad "2" smd roundrect
			(at 0.975 0 180)
			(size 0.85 2.3)
			(layers "F.Cu" "F.Mask" "F.Paste")
			(roundrect_rratio 0.1)
			(net 576 "/Supply/3V3_REG")
			(pintype "passive")
		)
	)
)
